# SCM (Grand Teton) — schematic netlist excerpt (pin names and nets, part order shuffled) for the footprints in the layout excerpt that follows; sources: Cadence DE-HDL packaged netlist, KiCad conversion of 12092022_DA0F0TMDCD0_F0T_Management_Board_D_brd_V3_OCP.brd

R203  Q_RES  10K 1% CHIP  pkg 0402LF  page 32 : A = P3V3_RGM ; B = JTAG_SCM_TMS

X17  TP_TDR_4P_FTS  TP_TDR_4P_DIP EMPTY  pkg TH  page 60
  S1  = TDR_DIFF_100_IN4_DP
  P1  = GND_P1
  P2  = GND_P1
  S2  = TDR_DIFF_100_IN4_DN

(kicad_pcb
	(version 20260206)
	(generator "pcbnew")
	(generator_version "10.0")
	(general
		(thickness 1.6)
		(legacy_teardrops no)
	)
	(paper "A4")
	(title_block
		(title "12092022_DA0F0TMDCD0_F0T_Management_Board_D_brd_V3_OCP.brd")
		(comment 1 "Grand Teton / footprints 509-510 of 1440")
	)
	(layers
		(0 "F.Cu" signal "TOP")
		(4 "In1.Cu" signal "GND")
		(6 "In2.Cu" signal "IN1")
		(8 "In3.Cu" signal "GND1")
		(10 "In4.Cu" signal "IN2")
		(12 "In5.Cu" signal "VCC")
		(14 "In6.Cu" signal "VCC1")
		(16 "In7.Cu" signal "IN3")
		(18 "In8.Cu" signal "GND2")
		(20 "In9.Cu" signal "IN4")
		(22 "In10.Cu" signal "GND3")
		(2 "B.Cu" signal "BOTTOM")
		(9 "F.Adhes" user "F.Adhesive")
		(11 "B.Adhes" user "B.Adhesive")
		(13 "F.Paste" user "Package Geometry/Pastemask Top")
		(15 "B.Paste" user "Package Geometry/Pastemask Bottom")
		(5 "F.SilkS" user "Ref Des/Silkscreen Top")
		(7 "B.SilkS" user "Ref Des/Silkscreen Bottom")
		(1 "F.Mask" user "Board Geometry/Soldermask Top")
		(3 "B.Mask" user "Board Geometry/Soldermask Bottom")
		(17 "Dwgs.User" user "User.Drawings")
		(19 "Cmts.User" user "User.Comments")
		(21 "Eco1.User" user "User.Eco1")
		(23 "Eco2.User" user "User.Eco2")
		(25 "Edge.Cuts" user "Board Geometry/Outline")
		(27 "Margin" user)
		(31 "F.CrtYd" user "Package Geometry/Place Bound Top")
		(29 "B.CrtYd" user "Package Geometry/Place Bound Bottom")
		(35 "F.Fab" user "Ref Des/Assembly Top")
		(33 "B.Fab" user "Ref Des/Assembly Bottom")
	)
	(footprint ""
		(layer "F.Cu")
		(at 112.014 62.23 90)
		(property "Reference" "X17"
			(at -2.07137 1.0795 0)
			(unlocked yes)
			(layer "F.SilkS")
			(effects
				(font
					(size 0.7874 0.5842)
					(thickness 0.1524)
				)
				(justify left)
			)
		)
		(property "Value" ""
			(at 0 0 90)
			(layer "F.Fab")
			(effects
				(font
					(size 1.27 1.27)
				)
			)
		)
		(property "Device Type" "TP_TDR_4P_FTS_TH-TP_TDR_4P_DIPA"
			(at 1.30175 1.27 180)
			(unlocked yes)
			(layer "F.Fab")
			(hide yes)
			(effects
				(font
					(size 0.635 0.4064)
					(thickness 0.1524)
				)
			)
		)
		(property "User Part Number" "N_A"
			(at 1.30175 1.27 180)
			(unlocked yes)
			(layer "Cmts.User")
			(hide yes)
			(effects
				(font
					(size 0.635 0.4064)
					(thickness 0.1524)
				)
			)
		)
		(duplicate_pad_numbers_are_jumpers no)
		(fp_line
			(start 2.54 -1.27)
			(end 0 -1.27)
			(stroke
				(width 0.1524)
				(type default)
			)
			(layer "F.SilkS")
		)
		(fp_line
			(start 0 -1.27)
			(end 0 -0.635)
			(stroke
				(width 0.1524)
				(type default)
			)
			(layer "F.SilkS")
		)
		(fp_line
			(start 2.54 -1.1303)
			(end 2.54 -1.27)
			(stroke
				(width 0.1524)
				(type default)
			)
			(layer "F.SilkS")
		)
		(fp_line
			(start 0 0.635)
			(end 0 1.905)
			(stroke
				(width 0.1524)
				(type default)
			)
			(layer "F.SilkS")
		)
		(fp_line
			(start 2.54 1.4097)
			(end 2.54 1.1303)
			(stroke
				(width 0.1524)
				(type default)
			)
			(layer "F.SilkS")
		)
		(fp_line
			(start 0 3.175)
			(end 0 3.81)
			(stroke
				(width 0.1524)
				(type default)
			)
			(layer "F.SilkS")
		)
		(fp_line
			(start 2.54 3.81)
			(end 2.54 3.6703)
			(stroke
				(width 0.1524)
				(type default)
			)
			(layer "F.SilkS")
		)
		(fp_line
			(start 0 3.81)
			(end 2.54 3.81)
			(stroke
				(width 0.1524)
				(type default)
			)
			(layer "F.SilkS")
		)
		(fp_poly
			(pts
				(xy -0.761746 0) (xy -2.285746 -0.762) (xy -2.285746 0.762)
			)
			(stroke
				(width 0)
				(type default)
			)
			(fill yes)
			(layer "F.SilkS")
		)
		(fp_line
			(start 2.54 -1.27)
			(end 0 -1.27)
			(stroke
				(width 0.1)
				(type default)
			)
			(layer "F.Fab")
		)
		(fp_line
			(start 0 -1.27)
			(end 0 3.81)
			(stroke
				(width 0.1)
				(type default)
			)
			(layer "F.Fab")
		)
		(fp_line
			(start 2.54 3.81)
			(end 2.54 -1.27)
			(stroke
				(width 0.1)
				(type default)
			)
			(layer "F.Fab")
		)
		(fp_line
			(start 0 3.81)
			(end 2.54 3.81)
			(stroke
				(width 0.1)
				(type default)
			)
			(layer "F.Fab")
		)
		(fp_poly
			(pts
				(xy -0.761746 0) (xy -2.285746 -0.762) (xy -2.285746 0.762)
			)
			(stroke
				(width 0)
				(type default)
			)
			(fill yes)
			(layer "F.Fab")
		)
		(pad "1" thru_hole circle
			(at 0 0 90)
			(size 1.0033 1.0033)
			(drill 0.249936)
			(layers "*.Cu" "*.Mask")
			(remove_unused_layers no)
			(net "TDR_DIFF_100_IN4_DP")
			(clearance 0.10795)
			(thermal_gap 0.10795)
			(padstack
				(mode front_inner_back)
				(layer "Inner"
					(shape circle)
					(size 0.8001 0.8001)
					(clearance 0.1524)
				)
				(layer "B.Cu"
					(shape circle)
					(size 1.0033 1.0033)
					(clearance 0.10795)
				)
			)
		)
		(pad "2" thru_hole circle
			(at 2.54 0 90)
			(size 1.9939 1.9939)
			(drill 0.249936)
			(layers "*.Cu" "*.Mask")
			(remove_unused_layers no)
			(net "GND_P1")
			(clearance 0.10795)
			(thermal_gap 0.10795)
			(padstack
				(mode front_inner_back)
				(layer "Inner"
					(shape circle)
					(size 0.8001 0.8001)
					(clearance 0.1524)
				)
				(layer "B.Cu"
					(shape circle)
					(size 1.9939 1.9939)
					(clearance 0.10795)
				)
			)
		)
		(pad "3" thru_hole circle
			(at 2.54 2.54 90)
			(size 1.9939 1.9939)
			(drill 0.249936)
			(layers "*.Cu" "*.Mask")
			(remove_unused_layers no)
			(net "GND_P1")
			(clearance 0.10795)
			(thermal_gap 0.10795)
			(padstack
				(mode front_inner_back)
				(layer "Inner"
					(shape circle)
					(size 0.8001 0.8001)
					(clearance 0.1524)
				)
				(layer "B.Cu"
					(shape circle)
					(size 1.9939 1.9939)
					(clearance 0.10795)
				)
			)
		)
		(pad "4" thru_hole circle
			(at 0 2.54 90)
			(size 1.0033 1.0033)
			(drill 0.249936)
			(layers "*.Cu" "*.Mask")
			(remove_unused_layers no)
			(net "TDR_DIFF_100_IN4_DN")
			(clearance 0.10795)
			(thermal_gap 0.10795)
			(padstack
				(mode front_inner_back)
				(layer "Inner"
					(shape circle)
					(size 0.8001 0.8001)
					(clearance 0.1524)
				)
				(layer "B.Cu"
					(shape circle)
					(size 1.0033 1.0033)
					(clearance 0.10795)
				)
			)
		)
	)
	(footprint ""
		(layer "F.Cu")
		(at 60.36437 -34.637726 90)
		(property "Reference" "R203"
			(at 0 0 90)
			(layer "F.SilkS")
			(hide yes)
			(effects
				(font
					(size 1.27 1.27)
				)
			)
		)
		(property "Value" ""
			(at 0 0 90)
			(layer "F.Fab")
			(effects
				(font
					(size 1.27 1.27)
				)
			)
		)
		(duplicate_pad_numbers_are_jumpers no)
		(fp_line
			(start 0.7874 -0.4064)
			(end 0.7874 0.4064)
			(stroke
				(width 0.1524)
				(type default)
			)
			(layer "F.SilkS")
		)
		(fp_line
			(start -0.7874 -0.4064)
			(end 0.7874 -0.4064)
			(stroke
				(width 0.1524)
				(type default)
			)
			(layer "F.SilkS")
		)
		(fp_line
			(start 0.7874 0.4064)
			(end -0.7874 0.4064)
			(stroke
				(width 0.1524)
				(type default)
			)
			(layer "F.SilkS")
		)
		(fp_line
			(start -0.7874 0.4064)
			(end -0.7874 -0.4064)
			(stroke
				(width 0.1524)
				(type default)
			)
			(layer "F.SilkS")
		)
		(fp_line
			(start -0.12065 -0.305054)
			(end -0.12065 -0.2794)
			(stroke
				(width 0.1)
				(type default)
			)
			(layer "F.Fab")
		)
		(fp_line
			(start -0.67945 -0.305054)
			(end -0.12065 -0.305054)
			(stroke
				(width 0.1)
				(type default)
			)
			(layer "F.Fab")
		)
		(fp_line
			(start 0.67945 -0.3048)
			(end 0.67945 0.3048)
			(stroke
				(width 0.1)
				(type default)
			)
			(layer "F.Fab")
		)
		(fp_line
			(start 0.12065 -0.3048)
			(end 0.67945 -0.3048)
			(stroke
				(width 0.1)
				(type default)
			)
			(layer "F.Fab")
		)
		(fp_line
			(start 0.12065 -0.2794)
			(end 0.12065 -0.3048)
			(stroke
				(width 0.1)
				(type default)
			)
			(layer "F.Fab")
		)
		(fp_line
			(start -0.12065 -0.2794)
			(end 0.12065 -0.2794)
			(stroke
				(width 0.1)
				(type default)
			)
			(layer "F.Fab")
		)
		(fp_line
			(start 0.120396 0.2794)
			(end -0.12065 0.2794)
			(stroke
				(width 0.1)
				(type default)
			)
			(layer "F.Fab")
		)
		(fp_line
			(start -0.12065 0.2794)
			(end -0.12065 0.3048)
			(stroke
				(width 0.1)
				(type default)
			)
			(layer "F.Fab")
		)
		(fp_line
			(start 0.67945 0.3048)
			(end 0.120396 0.3048)
			(stroke
				(width 0.1)
				(type default)
			)
			(layer "F.Fab")
		)
		(fp_line
			(start 0.120396 0.3048)
			(end 0.120396 0.2794)
			(stroke
				(width 0.1)
				(type default)
			)
			(layer "F.Fab")
		)
		(fp_line
			(start -0.12065 0.3048)
			(end -0.67945 0.3048)
			(stroke
				(width 0.1)
				(type default)
			)
			(layer "F.Fab")
		)
		(fp_line
			(start -0.67945 0.3048)
			(end -0.67945 -0.305054)
			(stroke
				(width 0.1)
				(type default)
			)
			(layer "F.Fab")
		)
		(pad "1" smd circle
			(at -0.40005 0 90)
			(size 0 0)
			(layers "F.Cu" "F.Mask" "F.Paste")
			(net "P3V3_RGM")
		)
		(pad "2" smd circle
			(at 0.40005 0 90)
			(size 0 0)
			(layers "F.Cu" "F.Mask" "F.Paste")
			(net "JTAG_SCM_TMS")
		)
	)
)
